# T6G (Grand Teton) — schematic netlist excerpt (pin names and nets, part order shuffled) for the footprints in the layout excerpt that follows; sources: Cadence DE-HDL packaged netlist, KiCad conversion of 04192023_DAF0TMB3IC0_F0TG_MB_C_brd_V02_OCP.brd

R1461  Q_RES  4.7K 5% EMPTY  pkg 0201LF  page 331 : A = P1V8_CPU1_RT_1D ; B = JTAG_TCK_RT_CPU1_P1
PR5  Q_RES  10K 1% CHIP  pkg 0402LF  page 193 : A = PVDDCR_CPU0_P0_VMON ; B = GND
R1327  Q_RES  1K 1% EMPTY  pkg 0402LF  page 357 : A = P3V3_AUX ; B = OCP_SFF_P3V3_P12V_ADC_R_ALERT

(kicad_pcb
	(version 20260206)
	(generator "pcbnew")
	(generator_version "10.0")
	(general
		(thickness 1.6)
		(legacy_teardrops no)
	)
	(paper "A4")
	(title_block
		(title "04192023_DAF0TMB3IC0_F0TG_MB_C_brd_V02_OCP.brd")
		(comment 1 "Grand Teton / footprints 2558-2560 of 8354")
	)
	(layers
		(0 "F.Cu" signal "TOP")
		(4 "In1.Cu" signal "GND")
		(6 "In2.Cu" signal "IN1")
		(8 "In3.Cu" signal "GND1")
		(10 "In4.Cu" signal "IN2")
		(12 "In5.Cu" signal "GND2")
		(14 "In6.Cu" signal "IN3")
		(16 "In7.Cu" signal "GND3")
		(18 "In8.Cu" signal "VCC")
		(20 "In9.Cu" signal "VCC1")
		(22 "In10.Cu" signal "GND4")
		(24 "In11.Cu" signal "IN4")
		(26 "In12.Cu" signal "GND5")
		(28 "In13.Cu" signal "IN5")
		(30 "In14.Cu" signal "GND6")
		(32 "In15.Cu" signal "IN6")
		(34 "In16.Cu" signal "GND7")
		(2 "B.Cu" signal "BOTTOM")
		(9 "F.Adhes" user "F.Adhesive")
		(11 "B.Adhes" user "B.Adhesive")
		(13 "F.Paste" user "Package Geometry/Pastemask Top")
		(15 "B.Paste" user "Package Geometry/Pastemask Bottom")
		(5 "F.SilkS" user "Ref Des/Silkscreen Top")
		(7 "B.SilkS" user "Ref Des/Silkscreen Bottom")
		(1 "F.Mask" user "Board Geometry/Soldermask Top")
		(3 "B.Mask" user "Board Geometry/Soldermask Bottom")
		(17 "Dwgs.User" user "User.Drawings")
		(19 "Cmts.User" user "User.Comments")
		(21 "Eco1.User" user "User.Eco1")
		(23 "Eco2.User" user "User.Eco2")
		(25 "Edge.Cuts" user "Board Geometry/Outline")
		(27 "Margin" user)
		(31 "F.CrtYd" user "Package Geometry/Place Bound Top")
		(29 "B.CrtYd" user "Package Geometry/Place Bound Bottom")
		(35 "F.Fab" user "Ref Des/Assembly Top")
		(33 "B.Fab" user "Ref Des/Assembly Bottom")
	)
	(footprint ""
		(layer "F.Cu")
		(at 96.0628 -416.4076 180)
		(property "Reference" "R1461"
			(at 0 0 180)
			(layer "F.SilkS")
			(hide yes)
			(effects
				(font
					(size 1.27 1.27)
				)
			)
		)
		(property "Value" ""
			(at 0 0 180)
			(layer "F.Fab")
			(effects
				(font
					(size 1.27 1.27)
				)
			)
		)
		(duplicate_pad_numbers_are_jumpers no)
		(fp_line
			(start 0.32512 0.175006)
			(end -0.32512 0.175006)
			(stroke
				(width 0.1)
				(type default)
			)
			(layer "F.Fab")
		)
		(fp_line
			(start 0.32512 -0.175006)
			(end 0.32512 0.175006)
			(stroke
				(width 0.1)
				(type default)
			)
			(layer "F.Fab")
		)
		(fp_line
			(start -0.32512 0.175006)
			(end -0.32512 -0.175006)
			(stroke
				(width 0.1)
				(type default)
			)
			(layer "F.Fab")
		)
		(fp_line
			(start -0.32512 -0.175006)
			(end 0.32512 -0.175006)
			(stroke
				(width 0.1)
				(type default)
			)
			(layer "F.Fab")
		)
		(pad "1" smd rect
			(at -0.2667 0 180)
			(size 0.3048 0.381)
			(layers "F.Cu" "F.Mask" "F.Paste")
			(net "P1V8_CPU1_RT_1D")
		)
		(pad "2" smd rect
			(at 0.2667 0)
			(size 0.3048 0.381)
			(layers "F.Cu" "F.Mask" "F.Paste")
			(net "JTAG_TCK_RT_CPU1_P1")
		)
	)
	(footprint ""
		(layer "F.Cu")
		(at 381.573278 -141.345158 180)
		(property "Reference" "PR5"
			(at 0 0 180)
			(layer "F.SilkS")
			(hide yes)
			(effects
				(font
					(size 1.27 1.27)
				)
			)
		)
		(property "Value" ""
			(at 0 0 180)
			(layer "F.Fab")
			(effects
				(font
					(size 1.27 1.27)
				)
			)
		)
		(duplicate_pad_numbers_are_jumpers no)
		(fp_line
			(start 0.7874 0.4064)
			(end -0.7874 0.4064)
			(stroke
				(width 0.1524)
				(type default)
			)
			(layer "F.SilkS")
		)
		(fp_line
			(start 0.7874 -0.4064)
			(end 0.7874 0.4064)
			(stroke
				(width 0.1524)
				(type default)
			)
			(layer "F.SilkS")
		)
		(fp_line
			(start -0.7874 0.4064)
			(end -0.7874 -0.4064)
			(stroke
				(width 0.1524)
				(type default)
			)
			(layer "F.SilkS")
		)
		(fp_line
			(start -0.7874 -0.4064)
			(end 0.7874 -0.4064)
			(stroke
				(width 0.1524)
				(type default)
			)
			(layer "F.SilkS")
		)
		(fp_line
			(start 0.67945 0.3048)
			(end 0.120396 0.3048)
			(stroke
				(width 0.1)
				(type default)
			)
			(layer "F.Fab")
		)
		(fp_line
			(start 0.67945 -0.3048)
			(end 0.67945 0.3048)
			(stroke
				(width 0.1)
				(type default)
			)
			(layer "F.Fab")
		)
		(fp_line
			(start 0.12065 -0.2794)
			(end 0.12065 -0.3048)
			(stroke
				(width 0.1)
				(type default)
			)
			(layer "F.Fab")
		)
		(fp_line
			(start 0.12065 -0.3048)
			(end 0.67945 -0.3048)
			(stroke
				(width 0.1)
				(type default)
			)
			(layer "F.Fab")
		)
		(fp_line
			(start 0.120396 0.3048)
			(end 0.120396 0.2794)
			(stroke
				(width 0.1)
				(type default)
			)
			(layer "F.Fab")
		)
		(fp_line
			(start 0.120396 0.2794)
			(end -0.12065 0.2794)
			(stroke
				(width 0.1)
				(type default)
			)
			(layer "F.Fab")
		)
		(fp_line
			(start -0.12065 0.3048)
			(end -0.67945 0.3048)
			(stroke
				(width 0.1)
				(type default)
			)
			(layer "F.Fab")
		)
		(fp_line
			(start -0.12065 0.2794)
			(end -0.12065 0.3048)
			(stroke
				(width 0.1)
				(type default)
			)
			(layer "F.Fab")
		)
		(fp_line
			(start -0.12065 -0.2794)
			(end 0.12065 -0.2794)
			(stroke
				(width 0.1)
				(type default)
			)
			(layer "F.Fab")
		)
		(fp_line
			(start -0.12065 -0.305054)
			(end -0.12065 -0.2794)
			(stroke
				(width 0.1)
				(type default)
			)
			(layer "F.Fab")
		)
		(fp_line
			(start -0.67945 0.3048)
			(end -0.67945 -0.305054)
			(stroke
				(width 0.1)
				(type default)
			)
			(layer "F.Fab")
		)
		(fp_line
			(start -0.67945 -0.305054)
			(end -0.12065 -0.305054)
			(stroke
				(width 0.1)
				(type default)
			)
			(layer "F.Fab")
		)
		(pad "1" smd circle
			(at -0.40005 0 180)
			(size 0 0)
			(layers "F.Cu" "F.Mask" "F.Paste")
			(net "PVDDCR_CPU0_P0_VMON")
		)
		(pad "2" smd circle
			(at 0.40005 0 180)
			(size 0 0)
			(layers "F.Cu" "F.Mask" "F.Paste")
			(net "GND")
		)
	)
	(footprint ""
		(layer "F.Cu")
		(at 391.290556 -73.359264 180)
		(property "Reference" "R1327"
			(at 0 0 180)
			(layer "F.SilkS")
			(hide yes)
			(effects
				(font
					(size 1.27 1.27)
				)
			)
		)
		(property "Value" ""
			(at 0 0 180)
			(layer "F.Fab")
			(effects
				(font
					(size 1.27 1.27)
				)
			)
		)
		(duplicate_pad_numbers_are_jumpers no)
		(fp_line
			(start 0.7874 0.4064)
			(end -0.7874 0.4064)
			(stroke
				(width 0.1524)
				(type default)
			)
			(layer "F.SilkS")
		)
		(fp_line
			(start 0.7874 -0.4064)
			(end 0.7874 0.4064)
			(stroke
				(width 0.1524)
				(type default)
			)
			(layer "F.SilkS")
		)
		(fp_line
			(start -0.7874 0.4064)
			(end -0.7874 -0.4064)
			(stroke
				(width 0.1524)
				(type default)
			)
			(layer "F.SilkS")
		)
		(fp_line
			(start -0.7874 -0.4064)
			(end 0.7874 -0.4064)
			(stroke
				(width 0.1524)
				(type default)
			)
			(layer "F.SilkS")
		)
		(fp_line
			(start 0.67945 0.3048)
			(end 0.120396 0.3048)
			(stroke
				(width 0.1)
				(type default)
			)
			(layer "F.Fab")
		)
		(fp_line
			(start 0.67945 -0.3048)
			(end 0.67945 0.3048)
			(stroke
				(width 0.1)
				(type default)
			)
			(layer "F.Fab")
		)
		(fp_line
			(start 0.12065 -0.2794)
			(end 0.12065 -0.3048)
			(stroke
				(width 0.1)
				(type default)
			)
			(layer "F.Fab")
		)
		(fp_line
			(start 0.12065 -0.3048)
			(end 0.67945 -0.3048)
			(stroke
				(width 0.1)
				(type default)
			)
			(layer "F.Fab")
		)
		(fp_line
			(start 0.120396 0.3048)
			(end 0.120396 0.2794)
			(stroke
				(width 0.1)
				(type default)
			)
			(layer "F.Fab")
		)
		(fp_line
			(start 0.120396 0.2794)
			(end -0.12065 0.2794)
			(stroke
				(width 0.1)
				(type default)
			)
			(layer "F.Fab")
		)
		(fp_line
			(start -0.12065 0.3048)
			(end -0.67945 0.3048)
			(stroke
				(width 0.1)
				(type default)
			)
			(layer "F.Fab")
		)
		(fp_line
			(start -0.12065 0.2794)
			(end -0.12065 0.3048)
			(stroke
				(width 0.1)
				(type default)
			)
			(layer "F.Fab")
		)
		(fp_line
			(start -0.12065 -0.2794)
			(end 0.12065 -0.2794)
			(stroke
				(width 0.1)
				(type default)
			)
			(layer "F.Fab")
		)
		(fp_line
			(start -0.12065 -0.305054)
			(end -0.12065 -0.2794)
			(stroke
				(width 0.1)
				(type default)
			)
			(layer "F.Fab")
		)
		(fp_line
			(start -0.67945 0.3048)
			(end -0.67945 -0.305054)
			(stroke
				(width 0.1)
				(type default)
			)
			(layer "F.Fab")
		)
		(fp_line
			(start -0.67945 -0.305054)
			(end -0.12065 -0.305054)
			(stroke
				(width 0.1)
				(type default)
			)
			(layer "F.Fab")
		)
		(pad "1" smd circle
			(at -0.40005 0 180)
			(size 0 0)
			(layers "F.Cu" "F.Mask" "F.Paste")
			(net "P3V3_AUX")
		)
		(pad "2" smd circle
			(at 0.40005 0 180)
			(size 0 0)
			(layers "F.Cu" "F.Mask" "F.Paste")
			(net "OCP_SFF_P3V3_P12V_ADC_R_ALERT")
		)
	)
)
